# S9S_MB_2U (Grand Teton) — schematic netlist excerpt (pin names and nets, part order shuffled) for the footprints in the layout excerpt that follows; sources: Cadence DE-HDL packaged netlist, KiCad conversion of 03242023_DA0F0TMBIJ0_F0T_Motherboard_J_brd_V01_OCP.brd

U345  NCT7718W  EMPTY  pkg MSOP8_0-65_3X3XE  page 305
  VDD  = P3V3_AUX
  \d+\  = P12V_HSC_TEMP_D+
  \d-\  = P12V_HSC_TEMP_D-
  \t_crit#\  = P12V_HSC_T_CRIT_N
  GND  = GND
  \alert#\  = P12V_HSC_TEMP_ALERT_N
  SDA  = P12V_HSC_TEMP_SDA
  SCL  = P12V_HSC_TEMP_SCL

R2221  Q_RES  26.7K 1% CHIP  pkg 0402LF  page 306 : A = P12V_AUX ; B = A_P12V_STBY_FP_TRIGGER

(kicad_pcb
	(version 20260206)
	(generator "pcbnew")
	(generator_version "10.0")
	(general
		(thickness 1.6)
		(legacy_teardrops no)
	)
	(paper "A4")
	(title_block
		(title "03242023_DA0F0TMBIJ0_F0T_Motherboard_J_brd_V01_OCP.brd")
		(comment 1 "Grand Teton / footprints 3694-3695 of 6105")
	)
	(layers
		(0 "F.Cu" signal "TOP")
		(4 "In1.Cu" signal "GND")
		(6 "In2.Cu" signal "IN1")
		(8 "In3.Cu" signal "GND1")
		(10 "In4.Cu" signal "IN2")
		(12 "In5.Cu" signal "GND2")
		(14 "In6.Cu" signal "IN3")
		(16 "In7.Cu" signal "GND3")
		(18 "In8.Cu" signal "VCC")
		(20 "In9.Cu" signal "VCC1")
		(22 "In10.Cu" signal "GND4")
		(24 "In11.Cu" signal "IN4")
		(26 "In12.Cu" signal "GND5")
		(28 "In13.Cu" signal "IN5")
		(30 "In14.Cu" signal "GND6")
		(32 "In15.Cu" signal "IN6")
		(34 "In16.Cu" signal "GND7")
		(2 "B.Cu" signal "BOTTOM")
		(9 "F.Adhes" user "F.Adhesive")
		(11 "B.Adhes" user "B.Adhesive")
		(13 "F.Paste" user "Package Geometry/Pastemask Top")
		(15 "B.Paste" user "Package Geometry/Pastemask Bottom")
		(5 "F.SilkS" user "Ref Des/Silkscreen Top")
		(7 "B.SilkS" user "Ref Des/Silkscreen Bottom")
		(1 "F.Mask" user "Board Geometry/Soldermask Top")
		(3 "B.Mask" user "Board Geometry/Soldermask Bottom")
		(17 "Dwgs.User" user "User.Drawings")
		(19 "Cmts.User" user "User.Comments")
		(21 "Eco1.User" user "User.Eco1")
		(23 "Eco2.User" user "User.Eco2")
		(25 "Edge.Cuts" user "Board Geometry/Outline")
		(27 "Margin" user)
		(31 "F.CrtYd" user "Package Geometry/Place Bound Top")
		(29 "B.CrtYd" user "Package Geometry/Place Bound Bottom")
		(35 "F.Fab" user "Ref Des/Assembly Top")
		(33 "B.Fab" user "Ref Des/Assembly Bottom")
	)
	(footprint ""
		(layer "F.Cu")
		(at 293.265098 -408.7749)
		(property "Reference" "U345"
			(at -0.37084 2.595372 0)
			(unlocked yes)
			(layer "F.SilkS")
			(effects
				(font
					(size 0.7874 0.5842)
					(thickness 0.1524)
				)
				(justify left)
			)
		)
		(property "Value" ""
			(at 0 0 0)
			(layer "F.Fab")
			(effects
				(font
					(size 1.27 1.27)
				)
			)
		)
		(duplicate_pad_numbers_are_jumpers no)
		(fp_line
			(start -1.448308 -1.549908)
			(end -0.774954 -1.549908)
			(stroke
				(width 0.1524)
				(type default)
			)
			(layer "F.SilkS")
		)
		(fp_line
			(start -1.448308 1.549908)
			(end -1.448308 -1.549908)
			(stroke
				(width 0.1524)
				(type default)
			)
			(layer "F.SilkS")
		)
		(fp_line
			(start -0.774954 -1.549908)
			(end 0 -0.533908)
			(stroke
				(width 0.1524)
				(type default)
			)
			(layer "F.SilkS")
		)
		(fp_line
			(start 0 -0.533908)
			(end 0.774954 -1.549908)
			(stroke
				(width 0.1524)
				(type default)
			)
			(layer "F.SilkS")
		)
		(fp_line
			(start 1.448308 -1.549908)
			(end 1.448308 1.549908)
			(stroke
				(width 0.1524)
				(type default)
			)
			(layer "F.SilkS")
		)
		(fp_line
			(start 1.448308 1.549908)
			(end -1.448308 1.549908)
			(stroke
				(width 0.1524)
				(type default)
			)
			(layer "F.SilkS")
		)
		(fp_rect
			(start -1.549908 -1.549908)
			(end -0.787908 -1.880108)
			(stroke
				(width 0)
				(type default)
			)
			(fill yes)
			(layer "F.SilkS")
		)
		(fp_line
			(start -1.549908 -1.549908)
			(end 1.549908 -1.549908)
			(stroke
				(width 0.1)
				(type default)
			)
			(layer "F.Fab")
		)
		(fp_line
			(start -1.549908 1.549908)
			(end -1.549908 -1.549908)
			(stroke
				(width 0.1)
				(type default)
			)
			(layer "F.Fab")
		)
		(fp_line
			(start 1.549908 -1.549908)
			(end 1.549908 1.549908)
			(stroke
				(width 0.1)
				(type default)
			)
			(layer "F.Fab")
		)
		(fp_line
			(start 1.549908 1.549908)
			(end -1.549908 1.549908)
			(stroke
				(width 0.1)
				(type default)
			)
			(layer "F.Fab")
		)
		(fp_rect
			(start -1.549908 -1.549908)
			(end -0.787908 -1.880108)
			(stroke
				(width 0)
				(type default)
			)
			(fill yes)
			(layer "F.Fab")
		)
		(pad "1" smd rect
			(at -2.350008 -0.975106 270)
			(size 0.4318 1.4986)
			(layers "F.Cu" "F.Mask" "F.Paste")
			(net "P3V3_AUX")
		)
		(pad "2" smd rect
			(at -2.350008 -0.32512 270)
			(size 0.4318 1.4986)
			(layers "F.Cu" "F.Mask" "F.Paste")
			(net "P12V_HSC_TEMP_D+")
		)
		(pad "3" smd rect
			(at -2.350008 0.32512 270)
			(size 0.4318 1.4986)
			(layers "F.Cu" "F.Mask" "F.Paste")
			(net "P12V_HSC_TEMP_D-")
		)
		(pad "4" smd rect
			(at -2.350008 0.975106 270)
			(size 0.4318 1.4986)
			(layers "F.Cu" "F.Mask" "F.Paste")
			(net "P12V_HSC_T_CRIT_N")
		)
		(pad "5" smd rect
			(at 2.350008 0.975106 270)
			(size 0.4318 1.4986)
			(layers "F.Cu" "F.Mask" "F.Paste")
			(net "GND")
		)
		(pad "6" smd rect
			(at 2.350008 0.32512 270)
			(size 0.4318 1.4986)
			(layers "F.Cu" "F.Mask" "F.Paste")
			(net "P12V_HSC_TEMP_ALERT_N")
		)
		(pad "7" smd rect
			(at 2.350008 -0.32512 270)
			(size 0.4318 1.4986)
			(layers "F.Cu" "F.Mask" "F.Paste")
			(net "P12V_HSC_TEMP_SDA")
		)
		(pad "8" smd rect
			(at 2.350008 -0.975106 270)
			(size 0.4318 1.4986)
			(layers "F.Cu" "F.Mask" "F.Paste")
			(net "P12V_HSC_TEMP_SCL")
		)
	)
	(footprint ""
		(layer "F.Cu")
		(at 220.087444 -98.164904 180)
		(property "Reference" "R2221"
			(at 0 0 180)
			(layer "F.SilkS")
			(hide yes)
			(effects
				(font
					(size 1.27 1.27)
				)
			)
		)
		(property "Value" ""
			(at 0 0 180)
			(layer "F.Fab")
			(effects
				(font
					(size 1.27 1.27)
				)
			)
		)
		(duplicate_pad_numbers_are_jumpers no)
		(fp_line
			(start 0.7874 0.4064)
			(end -0.7874 0.4064)
			(stroke
				(width 0.1524)
				(type default)
			)
			(layer "F.SilkS")
		)
		(fp_line
			(start 0.7874 -0.4064)
			(end 0.7874 0.4064)
			(stroke
				(width 0.1524)
				(type default)
			)
			(layer "F.SilkS")
		)
		(fp_line
			(start -0.7874 0.4064)
			(end -0.7874 -0.4064)
			(stroke
				(width 0.1524)
				(type default)
			)
			(layer "F.SilkS")
		)
		(fp_line
			(start -0.7874 -0.4064)
			(end 0.7874 -0.4064)
			(stroke
				(width 0.1524)
				(type default)
			)
			(layer "F.SilkS")
		)
		(fp_line
			(start 0.67945 0.3048)
			(end 0.120396 0.3048)
			(stroke
				(width 0.1)
				(type default)
			)
			(layer "F.Fab")
		)
		(fp_line
			(start 0.67945 -0.3048)
			(end 0.67945 0.3048)
			(stroke
				(width 0.1)
				(type default)
			)
			(layer "F.Fab")
		)
		(fp_line
			(start 0.12065 -0.2794)
			(end 0.12065 -0.3048)
			(stroke
				(width 0.1)
				(type default)
			)
			(layer "F.Fab")
		)
		(fp_line
			(start 0.12065 -0.3048)
			(end 0.67945 -0.3048)
			(stroke
				(width 0.1)
				(type default)
			)
			(layer "F.Fab")
		)
		(fp_line
			(start 0.120396 0.3048)
			(end 0.120396 0.2794)
			(stroke
				(width 0.1)
				(type default)
			)
			(layer "F.Fab")
		)
		(fp_line
			(start 0.120396 0.2794)
			(end -0.12065 0.2794)
			(stroke
				(width 0.1)
				(type default)
			)
			(layer "F.Fab")
		)
		(fp_line
			(start -0.12065 0.3048)
			(end -0.67945 0.3048)
			(stroke
				(width 0.1)
				(type default)
			)
			(layer "F.Fab")
		)
		(fp_line
			(start -0.12065 0.2794)
			(end -0.12065 0.3048)
			(stroke
				(width 0.1)
				(type default)
			)
			(layer "F.Fab")
		)
		(fp_line
			(start -0.12065 -0.2794)
			(end 0.12065 -0.2794)
			(stroke
				(width 0.1)
				(type default)
			)
			(layer "F.Fab")
		)
		(fp_line
			(start -0.12065 -0.305054)
			(end -0.12065 -0.2794)
			(stroke
				(width 0.1)
				(type default)
			)
			(layer "F.Fab")
		)
		(fp_line
			(start -0.67945 0.3048)
			(end -0.67945 -0.305054)
			(stroke
				(width 0.1)
				(type default)
			)
			(layer "F.Fab")
		)
		(fp_line
			(start -0.67945 -0.305054)
			(end -0.12065 -0.305054)
			(stroke
				(width 0.1)
				(type default)
			)
			(layer "F.Fab")
		)
		(pad "1" smd circle
			(at -0.40005 0 180)
			(size 0 0)
			(layers "F.Cu" "F.Mask" "F.Paste")
			(net "P12V_AUX")
		)
		(pad "2" smd circle
			(at 0.40005 0 180)
			(size 0 0)
			(layers "F.Cu" "F.Mask" "F.Paste")
			(net "A_P12V_STBY_FP_TRIGGER")
		)
	)
)
